(kicad_pcb
	(version 20260206)
	(generator "pcbnew")
	(generator_version "10.0")
	(general
		(thickness 1.6)
		(legacy_teardrops no)
	)
	(paper "A4")
	(title_block
		(title "Wiwynn_Tioga_Pass_MB.brd")
		(comment 1 "Tioga Pass / footprints 4594-4600 of 4770")
	)
	(layers
		(0 "F.Cu" signal "TOP")
		(4 "In1.Cu" signal "L2GND")
		(6 "In2.Cu" signal "L3")
		(8 "In3.Cu" signal "L4GND")
		(10 "In4.Cu" signal "L5")
		(12 "In5.Cu" signal "L6GND")
		(14 "In6.Cu" signal "L7VCC")
		(16 "In7.Cu" signal "L8VCC")
		(18 "In8.Cu" signal "L9GND")
		(20 "In9.Cu" signal "L10")
		(22 "In10.Cu" signal "L11GND")
		(24 "In11.Cu" signal "L12")
		(26 "In12.Cu" signal "L13GND")
		(2 "B.Cu" signal "BOTTOM")
		(9 "F.Adhes" user "F.Adhesive")
		(11 "B.Adhes" user "B.Adhesive")
		(13 "F.Paste" user "Package Geometry/Pastemask Top")
		(15 "B.Paste" user "Package Geometry/Pastemask Bottom")
		(5 "F.SilkS" user "Ref Des/Silkscreen Top")
		(7 "B.SilkS" user "Ref Des/Silkscreen Bottom")
		(1 "F.Mask" user "Board Geometry/Soldermask Top")
		(3 "B.Mask" user "Board Geometry/Soldermask Bottom")
		(17 "Dwgs.User" user "User.Drawings")
		(19 "Cmts.User" user "User.Comments")
		(21 "Eco1.User" user "User.Eco1")
		(23 "Eco2.User" user "User.Eco2")
		(25 "Edge.Cuts" user "Board Geometry/Outline")
		(27 "Margin" user)
		(31 "F.CrtYd" user "Package Geometry/Place Bound Top")
		(29 "B.CrtYd" user "Package Geometry/Place Bound Bottom")
		(35 "F.Fab" user "Ref Des/Assembly Top")
		(33 "B.Fab" user "Ref Des/Assembly Bottom")
	)
	(footprint ""
		(layer "B.Cu")
		(at 389.861806 -8.696452 -90)
		(property "Reference" "C32W3"
			(at 0.8382 -0.67818 270)
			(unlocked yes)
			(layer "B.SilkS")
			(effects
				(font
					(size 0.4064 0.254)
					(thickness 0.1524)
				)
				(justify left mirror)
			)
		)
		(property "Value" ""
			(at 0 0 90)
			(layer "B.Fab")
			(effects
				(font
					(size 1.27 1.27)
				)
				(justify mirror)
			)
		)
		(duplicate_pad_numbers_are_jumpers no)
		(fp_poly
			(pts
				(xy -0.3048 -0.1016) (xy -0.3048 0.9906) (xy 0.3048 0.9906) (xy 0.3048 -0.1016)
			)
			(stroke
				(width 0)
				(type default)
			)
			(fill no)
			(layer "B.CrtYd")
		)
		(fp_line
			(start -0.3048 0.9906)
			(end -0.3048 -0.1016)
			(stroke
				(width 0.1)
				(type default)
			)
			(layer "B.Fab")
		)
		(fp_line
			(start 0.3048 0.9906)
			(end -0.3048 0.9906)
			(stroke
				(width 0.1)
				(type default)
			)
			(layer "B.Fab")
		)
		(fp_line
			(start -0.3048 -0.1016)
			(end 0.3048 -0.1016)
			(stroke
				(width 0.1)
				(type default)
			)
			(layer "B.Fab")
		)
		(fp_line
			(start 0.3048 -0.1016)
			(end 0.3048 0.9906)
			(stroke
				(width 0.1)
				(type default)
			)
			(layer "B.Fab")
		)
		(pad "1" smd rect
			(at 0 0 90)
			(size 0.508 0.508)
			(layers "B.Cu" "B.Mask" "B.Paste")
			(net "P1V8_M2")
		)
		(pad "2" smd rect
			(at 0 0.889 90)
			(size 0.508 0.508)
			(layers "B.Cu" "B.Mask" "B.Paste")
			(net "GND")
		)
		(zone
			(layer "B.Cu")
			(hatch none 0.5)
			(connect_pads
				(clearance 0)
			)
			(min_thickness 0.25)
			(keepout
				(tracks not_allowed)
				(vias allowed)
				(pads allowed)
				(copperpour not_allowed)
				(footprints allowed)
			)
			(placement
				(enabled no)
				(sheetname "")
			)
			(fill
				(thermal_gap 0.5)
				(thermal_bridge_width 0.5)
				(island_removal_mode 0)
			)
			(polygon
				(pts
					(xy 389.226806 -8.442452) (xy 389.226806 -8.950452) (xy 389.607806 -8.950452) (xy 389.607806 -8.442452)
				)
			)
		)
		(zone
			(layer "B.Cu")
			(hatch none 0.5)
			(connect_pads
				(clearance 0)
			)
			(min_thickness 0.25)
			(keepout
				(tracks allowed)
				(vias not_allowed)
				(pads allowed)
				(copperpour not_allowed)
				(footprints allowed)
			)
			(placement
				(enabled no)
				(sheetname "")
			)
			(fill
				(thermal_gap 0.5)
				(thermal_bridge_width 0.5)
				(island_removal_mode 0)
			)
			(polygon
				(pts
					(xy 389.607806 -8.442452) (xy 389.607806 -8.950452) (xy 389.226806 -8.950452) (xy 389.226806 -8.442452)
				)
			)
		)
	)
	(footprint ""
		(layer "B.Cu")
		(at 361.188 -133.0198 180)
		(property "Reference" "R3M6"
			(at 0 0 0)
			(layer "B.SilkS")
			(hide yes)
			(effects
				(font
					(size 1.27 1.27)
				)
				(justify mirror)
			)
		)
		(property "Value" ""
			(at 0 0 0)
			(layer "B.Fab")
			(effects
				(font
					(size 1.27 1.27)
				)
				(justify mirror)
			)
		)
		(duplicate_pad_numbers_are_jumpers no)
		(fp_poly
			(pts
				(xy 0.2794 -0.1016) (xy -0.2794 -0.1016) (xy -0.2794 0.9906) (xy 0.2794 0.9906)
			)
			(stroke
				(width 0)
				(type default)
			)
			(fill no)
			(layer "B.CrtYd")
		)
		(fp_line
			(start 0.2794 0.9906)
			(end -0.2794 0.9906)
			(stroke
				(width 0.1)
				(type default)
			)
			(layer "B.Fab")
		)
		(fp_line
			(start 0.2794 -0.1016)
			(end 0.2794 0.9906)
			(stroke
				(width 0.1)
				(type default)
			)
			(layer "B.Fab")
		)
		(fp_line
			(start -0.2794 0.9906)
			(end -0.2794 -0.1016)
			(stroke
				(width 0.1)
				(type default)
			)
			(layer "B.Fab")
		)
		(fp_line
			(start -0.2794 -0.1016)
			(end 0.2794 -0.1016)
			(stroke
				(width 0.1)
				(type default)
			)
			(layer "B.Fab")
		)
		(pad "1" smd rect
			(at 0 0)
			(size 0.508 0.508)
			(layers "B.Cu" "B.Mask" "B.Paste")
			(net "FM_PVDDQ_DEF_EN")
		)
		(pad "2" smd rect
			(at 0 0.889)
			(size 0.508 0.508)
			(layers "B.Cu" "B.Mask" "B.Paste")
			(net "VR_PVDDQ_DEF_VREN")
		)
		(zone
			(layer "B.Cu")
			(hatch none 0.5)
			(connect_pads
				(clearance 0)
			)
			(min_thickness 0.25)
			(keepout
				(tracks not_allowed)
				(vias allowed)
				(pads allowed)
				(copperpour not_allowed)
				(footprints allowed)
			)
			(placement
				(enabled no)
				(sheetname "")
			)
			(fill
				(thermal_gap 0.5)
				(thermal_bridge_width 0.5)
				(island_removal_mode 0)
			)
			(polygon
				(pts
					(xy 360.934 -133.6548) (xy 361.442 -133.6548) (xy 361.442 -133.2738) (xy 360.934 -133.2738)
				)
			)
		)
		(zone
			(layer "B.Cu")
			(hatch none 0.5)
			(connect_pads
				(clearance 0)
			)
			(min_thickness 0.25)
			(keepout
				(tracks allowed)
				(vias not_allowed)
				(pads allowed)
				(copperpour not_allowed)
				(footprints allowed)
			)
			(placement
				(enabled no)
				(sheetname "")
			)
			(fill
				(thermal_gap 0.5)
				(thermal_bridge_width 0.5)
				(island_removal_mode 0)
			)
			(polygon
				(pts
					(xy 360.934 -133.2738) (xy 361.442 -133.2738) (xy 361.442 -133.6548) (xy 360.934 -133.6548)
				)
			)
		)
	)
	(footprint ""
		(layer "B.Cu")
		(at 386.709666 -45.691806 -90)
		(property "Reference" "R7E9"
			(at 0 0 90)
			(layer "B.SilkS")
			(hide yes)
			(effects
				(font
					(size 1.27 1.27)
				)
				(justify mirror)
			)
		)
		(property "Value" ""
			(at 0 0 90)
			(layer "B.Fab")
			(effects
				(font
					(size 1.27 1.27)
				)
				(justify mirror)
			)
		)
		(duplicate_pad_numbers_are_jumpers no)
		(fp_poly
			(pts
				(xy 0.2794 -0.1016) (xy -0.2794 -0.1016) (xy -0.2794 0.9906) (xy 0.2794 0.9906)
			)
			(stroke
				(width 0)
				(type default)
			)
			(fill no)
			(layer "B.CrtYd")
		)
		(fp_line
			(start -0.2794 0.9906)
			(end -0.2794 -0.1016)
			(stroke
				(width 0.1)
				(type default)
			)
			(layer "B.Fab")
		)
		(fp_line
			(start 0.2794 0.9906)
			(end -0.2794 0.9906)
			(stroke
				(width 0.1)
				(type default)
			)
			(layer "B.Fab")
		)
		(fp_line
			(start -0.2794 -0.1016)
			(end 0.2794 -0.1016)
			(stroke
				(width 0.1)
				(type default)
			)
			(layer "B.Fab")
		)
		(fp_line
			(start 0.2794 -0.1016)
			(end 0.2794 0.9906)
			(stroke
				(width 0.1)
				(type default)
			)
			(layer "B.Fab")
		)
		(pad "1" smd rect
			(at 0 0 90)
			(size 0.508 0.508)
			(layers "B.Cu" "B.Mask" "B.Paste")
			(net "FM_THROTTLE_N")
		)
		(pad "2" smd rect
			(at 0 0.889 90)
			(size 0.508 0.508)
			(layers "B.Cu" "B.Mask" "B.Paste")
			(net "FM_THROTTLE_R_N")
		)
		(zone
			(layer "B.Cu")
			(hatch none 0.5)
			(connect_pads
				(clearance 0)
			)
			(min_thickness 0.25)
			(keepout
				(tracks not_allowed)
				(vias allowed)
				(pads allowed)
				(copperpour not_allowed)
				(footprints allowed)
			)
			(placement
				(enabled no)
				(sheetname "")
			)
			(fill
				(thermal_gap 0.5)
				(thermal_bridge_width 0.5)
				(island_removal_mode 0)
			)
			(polygon
				(pts
					(xy 386.074666 -45.437806) (xy 386.074666 -45.945806) (xy 386.455666 -45.945806) (xy 386.455666 -45.437806)
				)
			)
		)
		(zone
			(layer "B.Cu")
			(hatch none 0.5)
			(connect_pads
				(clearance 0)
			)
			(min_thickness 0.25)
			(keepout
				(tracks allowed)
				(vias not_allowed)
				(pads allowed)
				(copperpour not_allowed)
				(footprints allowed)
			)
			(placement
				(enabled no)
				(sheetname "")
			)
			(fill
				(thermal_gap 0.5)
				(thermal_bridge_width 0.5)
				(island_removal_mode 0)
			)
			(polygon
				(pts
					(xy 386.455666 -45.437806) (xy 386.455666 -45.945806) (xy 386.074666 -45.945806) (xy 386.074666 -45.437806)
				)
			)
		)
	)
	(footprint ""
		(layer "B.Cu")
		(at 369.443 -109.601 -90)
		(property "Reference" "C3N13"
			(at 0 0 90)
			(layer "B.SilkS")
			(hide yes)
			(effects
				(font
					(size 1.27 1.27)
				)
				(justify mirror)
			)
		)
		(property "Value" ""
			(at 0 0 90)
			(layer "B.Fab")
			(effects
				(font
					(size 1.27 1.27)
				)
				(justify mirror)
			)
		)
		(duplicate_pad_numbers_are_jumpers no)
		(fp_poly
			(pts
				(xy -0.3048 -0.1016) (xy -0.3048 0.9906) (xy 0.3048 0.9906) (xy 0.3048 -0.1016)
			)
			(stroke
				(width 0)
				(type default)
			)
			(fill no)
			(layer "B.CrtYd")
		)
		(fp_line
			(start -0.3048 0.9906)
			(end -0.3048 -0.1016)
			(stroke
				(width 0.1)
				(type default)
			)
			(layer "B.Fab")
		)
		(fp_line
			(start 0.3048 0.9906)
			(end -0.3048 0.9906)
			(stroke
				(width 0.1)
				(type default)
			)
			(layer "B.Fab")
		)
		(fp_line
			(start -0.3048 -0.1016)
			(end 0.3048 -0.1016)
			(stroke
				(width 0.1)
				(type default)
			)
			(layer "B.Fab")
		)
		(fp_line
			(start 0.3048 -0.1016)
			(end 0.3048 0.9906)
			(stroke
				(width 0.1)
				(type default)
			)
			(layer "B.Fab")
		)
		(pad "1" smd rect
			(at 0 0 90)
			(size 0.508 0.508)
			(layers "B.Cu" "B.Mask" "B.Paste")
			(net "DMI_CPU0_PCH_RX_DN<3>")
		)
		(pad "2" smd rect
			(at 0 0.889 90)
			(size 0.508 0.508)
			(layers "B.Cu" "B.Mask" "B.Paste")
			(net "DMI_CPU0_PCH_RX_C_DN<3>")
		)
		(zone
			(layer "B.Cu")
			(hatch none 0.5)
			(connect_pads
				(clearance 0)
			)
			(min_thickness 0.25)
			(keepout
				(tracks not_allowed)
				(vias allowed)
				(pads allowed)
				(copperpour not_allowed)
				(footprints allowed)
			)
			(placement
				(enabled no)
				(sheetname "")
			)
			(fill
				(thermal_gap 0.5)
				(thermal_bridge_width 0.5)
				(island_removal_mode 0)
			)
			(polygon
				(pts
					(xy 368.808 -109.347) (xy 368.808 -109.855) (xy 369.189 -109.855) (xy 369.189 -109.347)
				)
			)
		)
		(zone
			(layer "B.Cu")
			(hatch none 0.5)
			(connect_pads
				(clearance 0)
			)
			(min_thickness 0.25)
			(keepout
				(tracks allowed)
				(vias not_allowed)
				(pads allowed)
				(copperpour not_allowed)
				(footprints allowed)
			)
			(placement
				(enabled no)
				(sheetname "")
			)
			(fill
				(thermal_gap 0.5)
				(thermal_bridge_width 0.5)
				(island_removal_mode 0)
			)
			(polygon
				(pts
					(xy 369.189 -109.347) (xy 369.189 -109.855) (xy 368.808 -109.855) (xy 368.808 -109.347)
				)
			)
		)
	)
	(footprint ""
		(layer "B.Cu")
		(at 87.158068 -12.954 -90)
		(property "Reference" "C5G81"
			(at -1.14681 0.76708 0)
			(unlocked yes)
			(layer "B.SilkS")
			(effects
				(font
					(size 0.7874 0.5842)
					(thickness 0.1524)
				)
				(justify mirror)
			)
		)
		(property "Value" ""
			(at 0 0 90)
			(layer "B.Fab")
			(effects
				(font
					(size 1.27 1.27)
				)
				(justify mirror)
			)
		)
		(duplicate_pad_numbers_are_jumpers no)
		(fp_rect
			(start 0.4953 1.6002)
			(end -0.4953 -0.2032)
			(stroke
				(width 0)
				(type default)
			)
			(fill no)
			(layer "B.CrtYd")
		)
		(fp_line
			(start -0.4953 1.6002)
			(end 0.4953 1.6002)
			(stroke
				(width 0.1)
				(type default)
			)
			(layer "B.Fab")
		)
		(fp_line
			(start 0.4953 1.6002)
			(end 0.4953 -0.2032)
			(stroke
				(width 0.1)
				(type default)
			)
			(layer "B.Fab")
		)
		(fp_line
			(start -0.4953 -0.2032)
			(end -0.4953 1.6002)
			(stroke
				(width 0.1)
				(type default)
			)
			(layer "B.Fab")
		)
		(fp_line
			(start 0.4953 -0.2032)
			(end -0.4953 -0.2032)
			(stroke
				(width 0.1)
				(type default)
			)
			(layer "B.Fab")
		)
		(pad "1" smd rect
			(at 0 0 90)
			(size 0.762 0.889)
			(layers "B.Cu" "B.Mask" "B.Paste")
			(net "PVDDQ_GHJ")
		)
		(pad "2" smd rect
			(at 0 1.397 90)
			(size 0.762 0.889)
			(layers "B.Cu" "B.Mask" "B.Paste")
			(net "GND")
		)
		(zone
			(layer "B.Cu")
			(hatch none 0.5)
			(connect_pads
				(clearance 0)
			)
			(min_thickness 0.25)
			(keepout
				(tracks not_allowed)
				(vias allowed)
				(pads allowed)
				(copperpour not_allowed)
				(footprints allowed)
			)
			(placement
				(enabled no)
				(sheetname "")
			)
			(fill
				(thermal_gap 0.5)
				(thermal_bridge_width 0.5)
				(island_removal_mode 0)
			)
			(polygon
				(pts
					(xy 86.205568 -12.573) (xy 86.713568 -12.573) (xy 86.713568 -13.335) (xy 86.205568 -13.335)
				)
			)
		)
	)
	(footprint ""
		(layer "B.Cu")
		(at 193.548 -144.4752 180)
		(property "Reference" "R6L13"
			(at 0 0 0)
			(layer "B.SilkS")
			(hide yes)
			(effects
				(font
					(size 1.27 1.27)
				)
				(justify mirror)
			)
		)
		(property "Value" ""
			(at 0 0 0)
			(layer "B.Fab")
			(effects
				(font
					(size 1.27 1.27)
				)
				(justify mirror)
			)
		)
		(duplicate_pad_numbers_are_jumpers no)
		(fp_poly
			(pts
				(xy 0.2794 -0.1016) (xy -0.2794 -0.1016) (xy -0.2794 0.9906) (xy 0.2794 0.9906)
			)
			(stroke
				(width 0)
				(type default)
			)
			(fill no)
			(layer "B.CrtYd")
		)
		(fp_line
			(start 0.2794 0.9906)
			(end -0.2794 0.9906)
			(stroke
				(width 0.1)
				(type default)
			)
			(layer "B.Fab")
		)
		(fp_line
			(start 0.2794 -0.1016)
			(end 0.2794 0.9906)
			(stroke
				(width 0.1)
				(type default)
			)
			(layer "B.Fab")
		)
		(fp_line
			(start -0.2794 0.9906)
			(end -0.2794 -0.1016)
			(stroke
				(width 0.1)
				(type default)
			)
			(layer "B.Fab")
		)
		(fp_line
			(start -0.2794 -0.1016)
			(end 0.2794 -0.1016)
			(stroke
				(width 0.1)
				(type default)
			)
			(layer "B.Fab")
		)
		(pad "1" smd rect
			(at 0 0)
			(size 0.508 0.508)
			(layers "B.Cu" "B.Mask" "B.Paste")
			(net "PVDDQ_DEF")
		)
		(pad "2" smd rect
			(at 0 0.889)
			(size 0.508 0.508)
			(layers "B.Cu" "B.Mask" "B.Paste")
			(net "M_E_VREF")
		)
		(zone
			(layer "B.Cu")
			(hatch none 0.5)
			(connect_pads
				(clearance 0)
			)
			(min_thickness 0.25)
			(keepout
				(tracks not_allowed)
				(vias allowed)
				(pads allowed)
				(copperpour not_allowed)
				(footprints allowed)
			)
			(placement
				(enabled no)
				(sheetname "")
			)
			(fill
				(thermal_gap 0.5)
				(thermal_bridge_width 0.5)
				(island_removal_mode 0)
			)
			(polygon
				(pts
					(xy 193.294 -145.1102) (xy 193.802 -145.1102) (xy 193.802 -144.7292) (xy 193.294 -144.7292)
				)
			)
		)
		(zone
			(layer "B.Cu")
			(hatch none 0.5)
			(connect_pads
				(clearance 0)
			)
			(min_thickness 0.25)
			(keepout
				(tracks allowed)
				(vias not_allowed)
				(pads allowed)
				(copperpour not_allowed)
				(footprints allowed)
			)
			(placement
				(enabled no)
				(sheetname "")
			)
			(fill
				(thermal_gap 0.5)
				(thermal_bridge_width 0.5)
				(island_removal_mode 0)
			)
			(polygon
				(pts
					(xy 193.294 -144.7292) (xy 193.802 -144.7292) (xy 193.802 -145.1102) (xy 193.294 -145.1102)
				)
			)
		)
	)
	(footprint ""
		(layer "B.Cu")
		(at 466.4583 -24.9555 -90)
		(property "Reference" "C2R11"
			(at 0 0 90)
			(layer "B.SilkS")
			(hide yes)
			(effects
				(font
					(size 1.27 1.27)
				)
				(justify mirror)
			)
		)
		(property "Value" "*"
			(at 0 -2.9337 270)
			(unlocked yes)
			(layer "B.Fab")
			(hide yes)
			(effects
				(font
					(size 1.27 1.016)
					(thickness 0.1524)
				)
				(justify mirror)
			)
		)
		(property "Device Type" "SC4D7U16V3KX-GP_SMD-BCG5-SC4D7A"
			(at 0 -4.4577 270)
			(unlocked yes)
			(layer "B.Fab")
			(hide yes)
			(effects
				(font
					(size 1.27 1.016)
					(thickness 0.1524)
				)
				(justify mirror)
			)
		)
		(duplicate_pad_numbers_are_jumpers no)
		(fp_line
			(start -0.508 0)
			(end 0.508 0)
			(stroke
				(width 0.2032)
				(type default)
			)
			(layer "B.SilkS")
		)
		(fp_rect
			(start 0.5842 1.3335)
			(end -0.5842 -1.3335)
			(stroke
				(width 0)
				(type default)
			)
			(fill no)
			(layer "B.CrtYd")
		)
		(fp_rect
			(start 0.5842 1.3335)
			(end -0.5842 -1.3335)
			(stroke
				(width 0)
				(type default)
			)
			(fill no)
			(layer "B.Fab")
		)
		(pad "1" smd custom
			(at 0 -0.762 90)
			(size 0.2159 0.2159)
			(layers "B.Cu" "B.Mask" "B.Paste")
			(net "P5V_STBY")
			(options
				(clearance outline)
				(anchor circle)
			)
			(primitives
				(gr_poly
					(pts
						(arc
							(start -0.3302 0.4318)
							(mid -0.402042 0.402042)
							(end -0.4318 0.3302)
						)
						(arc
							(start -0.4318 -0.3302)
							(mid -0.402042 -0.402042)
							(end -0.3302 -0.4318)
						)
						(arc
							(start 0.3302 -0.4318)
							(mid 0.402042 -0.402042)
							(end 0.4318 -0.3302)
						)
						(arc
							(start 0.4318 0.3302)
							(mid 0.402042 0.402042)
							(end 0.3302 0.4318)
						)
					)
					(width 0)
					(fill yes)
				)
			)
		)
		(pad "2" smd custom
			(at 0 0.762 90)
			(size 0.2159 0.2159)
			(layers "B.Cu" "B.Mask" "B.Paste")
			(net "AGND_P3V3_STBY")
			(options
				(clearance outline)
				(anchor circle)
			)
			(primitives
				(gr_poly
					(pts
						(arc
							(start -0.3302 0.4318)
							(mid -0.402042 0.402042)
							(end -0.4318 0.3302)
						)
						(arc
							(start -0.4318 -0.3302)
							(mid -0.402042 -0.402042)
							(end -0.3302 -0.4318)
						)
						(arc
							(start 0.3302 -0.4318)
							(mid 0.402042 -0.402042)
							(end 0.4318 -0.3302)
						)
						(arc
							(start 0.4318 0.3302)
							(mid 0.402042 0.402042)
							(end 0.3302 0.4318)
						)
					)
					(width 0)
					(fill yes)
				)
			)
		)
	)
)
